(kicad_pcb
	(version 20260206)
	(generator "pcbnew")
	(generator_version "10.0")
	(general
		(thickness 1.6)
		(legacy_teardrops no)
	)
	(paper "A4")
	(title_block
		(title "03242023_DA0F0TMBIJ0_F0T_Motherboard_J_brd_V01_OCP.brd")
		(comment 1 "Grand Teton / footprint 2188 of 6105 (J19), pads 113-224 of 291")
	)
	(layers
		(0 "F.Cu" signal "TOP")
		(4 "In1.Cu" signal "GND")
		(6 "In2.Cu" signal "IN1")
		(8 "In3.Cu" signal "GND1")
		(10 "In4.Cu" signal "IN2")
		(12 "In5.Cu" signal "GND2")
		(14 "In6.Cu" signal "IN3")
		(16 "In7.Cu" signal "GND3")
		(18 "In8.Cu" signal "VCC")
		(20 "In9.Cu" signal "VCC1")
		(22 "In10.Cu" signal "GND4")
		(24 "In11.Cu" signal "IN4")
		(26 "In12.Cu" signal "GND5")
		(28 "In13.Cu" signal "IN5")
		(30 "In14.Cu" signal "GND6")
		(32 "In15.Cu" signal "IN6")
		(34 "In16.Cu" signal "GND7")
		(2 "B.Cu" signal "BOTTOM")
		(9 "F.Adhes" user "F.Adhesive")
		(11 "B.Adhes" user "B.Adhesive")
		(13 "F.Paste" user "Package Geometry/Pastemask Top")
		(15 "B.Paste" user "Package Geometry/Pastemask Bottom")
		(5 "F.SilkS" user "Ref Des/Silkscreen Top")
		(7 "B.SilkS" user "Ref Des/Silkscreen Bottom")
		(1 "F.Mask" user "Board Geometry/Soldermask Top")
		(3 "B.Mask" user "Board Geometry/Soldermask Bottom")
		(17 "Dwgs.User" user "User.Drawings")
		(19 "Cmts.User" user "User.Comments")
		(21 "Eco1.User" user "User.Eco1")
		(23 "Eco2.User" user "User.Eco2")
		(25 "Edge.Cuts" user "Board Geometry/Outline")
		(27 "Margin" user)
		(31 "F.CrtYd" user "Package Geometry/Place Bound Top")
		(29 "B.CrtYd" user "Package Geometry/Place Bound Bottom")
		(35 "F.Fab" user "Ref Des/Assembly Top")
		(33 "B.Fab" user "Ref Des/Assembly Bottom")
	)
	(footprint ""
		(layer "F.Cu")
		(at 40.36568 -258.091686)
		(property "Reference" "J19"
			(at -5.21716 -81.970372 0)
			(unlocked yes)
			(layer "F.SilkS")
			(effects
				(font
					(size 0.7874 0.5842)
					(thickness 0.1524)
				)
				(justify left)
			)
		)
		(property "Value" ""
			(at 0 0 0)
			(layer "F.Fab")
			(effects
				(font
					(size 1.27 1.27)
				)
			)
		)
		(duplicate_pad_numbers_are_jumpers no)
		(pad "113" smd rect
			(at -2.050034 36.975034 270)
			(size 0.519938 1.4986)
			(layers "F.Cu" "F.Mask" "F.Paste")
			(net "M_B_CPU1_SB_DQ<9>")
		)
		(pad "114" smd rect
			(at -2.050034 37.824918 270)
			(size 0.519938 1.4986)
			(layers "F.Cu" "F.Mask" "F.Paste")
			(net "GND")
		)
		(pad "115" smd rect
			(at -2.050034 38.675056 270)
			(size 0.519938 1.4986)
			(layers "F.Cu" "F.Mask" "F.Paste")
			(net "M_B_CPU1_SB_DQS_DP<1>")
		)
		(pad "116" smd rect
			(at -2.050034 39.52494 270)
			(size 0.519938 1.4986)
			(layers "F.Cu" "F.Mask" "F.Paste")
			(net "M_B_CPU1_SB_DQS_DN<1>")
		)
		(pad "117" smd rect
			(at -2.050034 40.375078 270)
			(size 0.519938 1.4986)
			(layers "F.Cu" "F.Mask" "F.Paste")
			(net "GND")
		)
		(pad "118" smd rect
			(at -2.050034 41.224962 270)
			(size 0.519938 1.4986)
			(layers "F.Cu" "F.Mask" "F.Paste")
			(net "M_B_CPU1_SB_DQ<12>")
		)
		(pad "119" smd rect
			(at -2.050034 42.0751 270)
			(size 0.519938 1.4986)
			(layers "F.Cu" "F.Mask" "F.Paste")
			(net "GND")
		)
		(pad "120" smd rect
			(at -2.050034 42.924984 270)
			(size 0.519938 1.4986)
			(layers "F.Cu" "F.Mask" "F.Paste")
			(net "M_B_CPU1_SB_DQ<13>")
		)
		(pad "121" smd rect
			(at -2.050034 43.775122 270)
			(size 0.519938 1.4986)
			(layers "F.Cu" "F.Mask" "F.Paste")
			(net "GND")
		)
		(pad "122" smd rect
			(at -2.050034 44.625006 270)
			(size 0.519938 1.4986)
			(layers "F.Cu" "F.Mask" "F.Paste")
			(net "M_B_CPU1_SB_DQ<16>")
		)
		(pad "123" smd rect
			(at -2.050034 45.47489 270)
			(size 0.519938 1.4986)
			(layers "F.Cu" "F.Mask" "F.Paste")
			(net "GND")
		)
		(pad "124" smd rect
			(at -2.050034 46.325028 270)
			(size 0.519938 1.4986)
			(layers "F.Cu" "F.Mask" "F.Paste")
			(net "M_B_CPU1_SB_DQ<17>")
		)
		(pad "125" smd rect
			(at -2.050034 47.174912 270)
			(size 0.519938 1.4986)
			(layers "F.Cu" "F.Mask" "F.Paste")
			(net "GND")
		)
		(pad "126" smd rect
			(at -2.050034 48.02505 270)
			(size 0.519938 1.4986)
			(layers "F.Cu" "F.Mask" "F.Paste")
			(net "M_B_CPU1_SB_DQS_DP<2>")
		)
		(pad "127" smd rect
			(at -2.050034 48.874934 270)
			(size 0.519938 1.4986)
			(layers "F.Cu" "F.Mask" "F.Paste")
			(net "M_B_CPU1_SB_DQS_DN<2>")
		)
		(pad "128" smd rect
			(at -2.050034 49.725072 270)
			(size 0.519938 1.4986)
			(layers "F.Cu" "F.Mask" "F.Paste")
			(net "GND")
		)
		(pad "129" smd rect
			(at -2.050034 50.574956 270)
			(size 0.519938 1.4986)
			(layers "F.Cu" "F.Mask" "F.Paste")
			(net "M_B_CPU1_SB_DQ<20>")
		)
		(pad "130" smd rect
			(at -2.050034 51.425094 270)
			(size 0.519938 1.4986)
			(layers "F.Cu" "F.Mask" "F.Paste")
			(net "GND")
		)
		(pad "131" smd rect
			(at -2.050034 52.274978 270)
			(size 0.519938 1.4986)
			(layers "F.Cu" "F.Mask" "F.Paste")
			(net "M_B_CPU1_SB_DQ<21>")
		)
		(pad "132" smd rect
			(at -2.050034 53.125116 270)
			(size 0.519938 1.4986)
			(layers "F.Cu" "F.Mask" "F.Paste")
			(net "GND")
		)
		(pad "133" smd rect
			(at -2.050034 53.975 270)
			(size 0.519938 1.4986)
			(layers "F.Cu" "F.Mask" "F.Paste")
			(net "M_B_CPU1_SB_DQ<24>")
		)
		(pad "134" smd rect
			(at -2.050034 54.824884 270)
			(size 0.519938 1.4986)
			(layers "F.Cu" "F.Mask" "F.Paste")
			(net "GND")
		)
		(pad "135" smd rect
			(at -2.050034 55.675022 270)
			(size 0.519938 1.4986)
			(layers "F.Cu" "F.Mask" "F.Paste")
			(net "M_B_CPU1_SB_DQ<25>")
		)
		(pad "136" smd rect
			(at -2.050034 56.524906 270)
			(size 0.519938 1.4986)
			(layers "F.Cu" "F.Mask" "F.Paste")
			(net "GND")
		)
		(pad "137" smd rect
			(at -2.050034 57.375044 270)
			(size 0.519938 1.4986)
			(layers "F.Cu" "F.Mask" "F.Paste")
			(net "M_B_CPU1_SB_DQS_DP<3>")
		)
		(pad "138" smd rect
			(at -2.050034 58.224928 270)
			(size 0.519938 1.4986)
			(layers "F.Cu" "F.Mask" "F.Paste")
			(net "M_B_CPU1_SB_DQS_DN<3>")
		)
		(pad "139" smd rect
			(at -2.050034 59.075066 270)
			(size 0.519938 1.4986)
			(layers "F.Cu" "F.Mask" "F.Paste")
			(net "GND")
		)
		(pad "140" smd rect
			(at -2.050034 59.92495 270)
			(size 0.519938 1.4986)
			(layers "F.Cu" "F.Mask" "F.Paste")
			(net "M_B_CPU1_SB_DQ<28>")
		)
		(pad "141" smd rect
			(at -2.050034 60.775088 270)
			(size 0.519938 1.4986)
			(layers "F.Cu" "F.Mask" "F.Paste")
			(net "GND")
		)
		(pad "142" smd rect
			(at -2.050034 61.624972 270)
			(size 0.519938 1.4986)
			(layers "F.Cu" "F.Mask" "F.Paste")
			(net "M_B_CPU1_SB_DQ<29>")
		)
		(pad "143" smd rect
			(at -2.050034 62.47511 270)
			(size 0.519938 1.4986)
			(layers "F.Cu" "F.Mask" "F.Paste")
			(net "GND")
		)
		(pad "144" smd rect
			(at -2.050034 63.324994 270)
			(size 0.519938 1.4986)
			(layers "F.Cu" "F.Mask" "F.Paste")
			(net "TP_CHB_CPU1_DIMM1_FRU_1")
		)
		(pad "145" smd rect
			(at 2.050034 -63.324994 270)
			(size 0.519938 1.4986)
			(layers "F.Cu" "F.Mask" "F.Paste")
			(net "P12V_S3_AUX_CPU1_NVDIMM")
		)
		(pad "146" smd rect
			(at 2.050034 -62.47511 270)
			(size 0.519938 1.4986)
			(layers "F.Cu" "F.Mask" "F.Paste")
			(net "P12V_S3_AUX_CPU1_NVDIMM")
		)
		(pad "147" smd rect
			(at 2.050034 -61.624972 270)
			(size 0.519938 1.4986)
			(layers "F.Cu" "F.Mask" "F.Paste")
			(net "PWRGD_CHB_CPU1_DIMM1")
		)
		(pad "148" smd rect
			(at 2.050034 -60.775088 270)
			(size 0.519938 1.4986)
			(layers "F.Cu" "F.Mask" "F.Paste")
			(net "PD_CHB_CPU1_DIMM1_SAA")
		)
		(pad "149" smd rect
			(at 2.050034 -59.92495 270)
			(size 0.519938 1.4986)
			(layers "F.Cu" "F.Mask" "F.Paste")
			(net "TP_CHB_CPU1_DIMM1_FRU_2")
		)
		(pad "150" smd rect
			(at 2.050034 -59.075066 270)
			(size 0.519938 1.4986)
			(layers "F.Cu" "F.Mask" "F.Paste")
			(net "TP_CHB_CPU1_DIMM1_FRU_3")
		)
		(pad "151" smd rect
			(at 2.050034 -58.224928 270)
			(size 0.519938 1.4986)
			(layers "F.Cu" "F.Mask" "F.Paste")
			(net "GND")
		)
		(pad "152" smd rect
			(at 2.050034 -57.375044 270)
			(size 0.519938 1.4986)
			(layers "F.Cu" "F.Mask" "F.Paste")
			(net "M_B_CPU1_SA_DQ<2>")
		)
		(pad "153" smd rect
			(at 2.050034 -56.524906 270)
			(size 0.519938 1.4986)
			(layers "F.Cu" "F.Mask" "F.Paste")
			(net "GND")
		)
		(pad "154" smd rect
			(at 2.050034 -55.675022 270)
			(size 0.519938 1.4986)
			(layers "F.Cu" "F.Mask" "F.Paste")
			(net "M_B_CPU1_SA_DQ<3>")
		)
		(pad "155" smd rect
			(at 2.050034 -54.824884 270)
			(size 0.519938 1.4986)
			(layers "F.Cu" "F.Mask" "F.Paste")
			(net "GND")
		)
		(pad "156" smd rect
			(at 2.050034 -53.975 270)
			(size 0.519938 1.4986)
			(layers "F.Cu" "F.Mask" "F.Paste")
			(net "M_B_CPU1_SA_DQS_DN<5>")
		)
		(pad "157" smd rect
			(at 2.050034 -53.125116 270)
			(size 0.519938 1.4986)
			(layers "F.Cu" "F.Mask" "F.Paste")
			(net "M_B_CPU1_SA_DQS_DP<5>")
		)
		(pad "158" smd rect
			(at 2.050034 -52.274978 270)
			(size 0.519938 1.4986)
			(layers "F.Cu" "F.Mask" "F.Paste")
			(net "GND")
		)
		(pad "159" smd rect
			(at 2.050034 -51.425094 270)
			(size 0.519938 1.4986)
			(layers "F.Cu" "F.Mask" "F.Paste")
			(net "M_B_CPU1_SA_DQ<6>")
		)
		(pad "160" smd rect
			(at 2.050034 -50.574956 270)
			(size 0.519938 1.4986)
			(layers "F.Cu" "F.Mask" "F.Paste")
			(net "GND")
		)
		(pad "161" smd rect
			(at 2.050034 -49.725072 270)
			(size 0.519938 1.4986)
			(layers "F.Cu" "F.Mask" "F.Paste")
			(net "M_B_CPU1_SA_DQ<7>")
		)
		(pad "162" smd rect
			(at 2.050034 -48.874934 270)
			(size 0.519938 1.4986)
			(layers "F.Cu" "F.Mask" "F.Paste")
			(net "GND")
		)
		(pad "163" smd rect
			(at 2.050034 -48.02505 270)
			(size 0.519938 1.4986)
			(layers "F.Cu" "F.Mask" "F.Paste")
			(net "M_B_CPU1_SA_DQ<10>")
		)
		(pad "164" smd rect
			(at 2.050034 -47.174912 270)
			(size 0.519938 1.4986)
			(layers "F.Cu" "F.Mask" "F.Paste")
			(net "GND")
		)
		(pad "165" smd rect
			(at 2.050034 -46.325028 270)
			(size 0.519938 1.4986)
			(layers "F.Cu" "F.Mask" "F.Paste")
			(net "M_B_CPU1_SA_DQ<11>")
		)
		(pad "166" smd rect
			(at 2.050034 -45.47489 270)
			(size 0.519938 1.4986)
			(layers "F.Cu" "F.Mask" "F.Paste")
			(net "GND")
		)
		(pad "167" smd rect
			(at 2.050034 -44.625006 270)
			(size 0.519938 1.4986)
			(layers "F.Cu" "F.Mask" "F.Paste")
			(net "M_B_CPU1_SA_DQS_DN<6>")
		)
		(pad "168" smd rect
			(at 2.050034 -43.775122 270)
			(size 0.519938 1.4986)
			(layers "F.Cu" "F.Mask" "F.Paste")
			(net "M_B_CPU1_SA_DQS_DP<6>")
		)
		(pad "169" smd rect
			(at 2.050034 -42.924984 270)
			(size 0.519938 1.4986)
			(layers "F.Cu" "F.Mask" "F.Paste")
			(net "GND")
		)
		(pad "170" smd rect
			(at 2.050034 -42.0751 270)
			(size 0.519938 1.4986)
			(layers "F.Cu" "F.Mask" "F.Paste")
			(net "M_B_CPU1_SA_DQ<14>")
		)
		(pad "171" smd rect
			(at 2.050034 -41.224962 270)
			(size 0.519938 1.4986)
			(layers "F.Cu" "F.Mask" "F.Paste")
			(net "GND")
		)
		(pad "172" smd rect
			(at 2.050034 -40.375078 270)
			(size 0.519938 1.4986)
			(layers "F.Cu" "F.Mask" "F.Paste")
			(net "M_B_CPU1_SA_DQ<15>")
		)
		(pad "173" smd rect
			(at 2.050034 -39.52494 270)
			(size 0.519938 1.4986)
			(layers "F.Cu" "F.Mask" "F.Paste")
			(net "GND")
		)
		(pad "174" smd rect
			(at 2.050034 -38.675056 270)
			(size 0.519938 1.4986)
			(layers "F.Cu" "F.Mask" "F.Paste")
			(net "M_B_CPU1_SA_DQ<18>")
		)
		(pad "175" smd rect
			(at 2.050034 -37.824918 270)
			(size 0.519938 1.4986)
			(layers "F.Cu" "F.Mask" "F.Paste")
			(net "GND")
		)
		(pad "176" smd rect
			(at 2.050034 -36.975034 270)
			(size 0.519938 1.4986)
			(layers "F.Cu" "F.Mask" "F.Paste")
			(net "M_B_CPU1_SA_DQ<19>")
		)
		(pad "177" smd rect
			(at 2.050034 -36.124896 270)
			(size 0.519938 1.4986)
			(layers "F.Cu" "F.Mask" "F.Paste")
			(net "GND")
		)
		(pad "178" smd rect
			(at 2.050034 -35.275012 270)
			(size 0.519938 1.4986)
			(layers "F.Cu" "F.Mask" "F.Paste")
			(net "M_B_CPU1_SA_DQS_DN<7>")
		)
		(pad "179" smd rect
			(at 2.050034 -34.425128 270)
			(size 0.519938 1.4986)
			(layers "F.Cu" "F.Mask" "F.Paste")
			(net "M_B_CPU1_SA_DQS_DP<7>")
		)
		(pad "180" smd rect
			(at 2.050034 -33.57499 270)
			(size 0.519938 1.4986)
			(layers "F.Cu" "F.Mask" "F.Paste")
			(net "GND")
		)
		(pad "181" smd rect
			(at 2.050034 -32.725106 270)
			(size 0.519938 1.4986)
			(layers "F.Cu" "F.Mask" "F.Paste")
			(net "M_B_CPU1_SA_DQ<22>")
		)
		(pad "182" smd rect
			(at 2.050034 -31.874968 270)
			(size 0.519938 1.4986)
			(layers "F.Cu" "F.Mask" "F.Paste")
			(net "GND")
		)
		(pad "183" smd rect
			(at 2.050034 -31.025084 270)
			(size 0.519938 1.4986)
			(layers "F.Cu" "F.Mask" "F.Paste")
			(net "M_B_CPU1_SA_DQ<23>")
		)
		(pad "184" smd rect
			(at 2.050034 -30.174946 270)
			(size 0.519938 1.4986)
			(layers "F.Cu" "F.Mask" "F.Paste")
			(net "GND")
		)
		(pad "185" smd rect
			(at 2.050034 -29.325062 270)
			(size 0.519938 1.4986)
			(layers "F.Cu" "F.Mask" "F.Paste")
			(net "M_B_CPU1_SA_DQ<26>")
		)
		(pad "186" smd rect
			(at 2.050034 -28.474924 270)
			(size 0.519938 1.4986)
			(layers "F.Cu" "F.Mask" "F.Paste")
			(net "GND")
		)
		(pad "187" smd rect
			(at 2.050034 -27.62504 270)
			(size 0.519938 1.4986)
			(layers "F.Cu" "F.Mask" "F.Paste")
			(net "M_B_CPU1_SA_DQ<27>")
		)
		(pad "188" smd rect
			(at 2.050034 -26.774902 270)
			(size 0.519938 1.4986)
			(layers "F.Cu" "F.Mask" "F.Paste")
			(net "GND")
		)
		(pad "189" smd rect
			(at 2.050034 -25.925018 270)
			(size 0.519938 1.4986)
			(layers "F.Cu" "F.Mask" "F.Paste")
			(net "M_B_CPU1_SA_DQS_DN<8>")
		)
		(pad "190" smd rect
			(at 2.050034 -25.07488 270)
			(size 0.519938 1.4986)
			(layers "F.Cu" "F.Mask" "F.Paste")
			(net "M_B_CPU1_SA_DQS_DP<8>")
		)
		(pad "191" smd rect
			(at 2.050034 -24.224996 270)
			(size 0.519938 1.4986)
			(layers "F.Cu" "F.Mask" "F.Paste")
			(net "GND")
		)
		(pad "192" smd rect
			(at 2.050034 -23.375112 270)
			(size 0.519938 1.4986)
			(layers "F.Cu" "F.Mask" "F.Paste")
			(net "M_B_CPU1_SA_DQ<30>")
		)
		(pad "193" smd rect
			(at 2.050034 -22.524974 270)
			(size 0.519938 1.4986)
			(layers "F.Cu" "F.Mask" "F.Paste")
			(net "GND")
		)
		(pad "194" smd rect
			(at 2.050034 -21.67509 270)
			(size 0.519938 1.4986)
			(layers "F.Cu" "F.Mask" "F.Paste")
			(net "M_B_CPU1_SA_DQ<31>")
		)
		(pad "195" smd rect
			(at 2.050034 -20.824952 270)
			(size 0.519938 1.4986)
			(layers "F.Cu" "F.Mask" "F.Paste")
			(net "GND")
		)
		(pad "196" smd rect
			(at 2.050034 -19.975068 270)
			(size 0.519938 1.4986)
			(layers "F.Cu" "F.Mask" "F.Paste")
			(net "M_B_CPU1_SA_CB<2>")
		)
		(pad "197" smd rect
			(at 2.050034 -19.12493 270)
			(size 0.519938 1.4986)
			(layers "F.Cu" "F.Mask" "F.Paste")
			(net "GND")
		)
		(pad "198" smd rect
			(at 2.050034 -18.275046 270)
			(size 0.519938 1.4986)
			(layers "F.Cu" "F.Mask" "F.Paste")
			(net "M_B_CPU1_SA_CB<3>")
		)
		(pad "199" smd rect
			(at 2.050034 -17.424908 270)
			(size 0.519938 1.4986)
			(layers "F.Cu" "F.Mask" "F.Paste")
			(net "GND")
		)
		(pad "200" smd rect
			(at 2.050034 -16.575024 270)
			(size 0.519938 1.4986)
			(layers "F.Cu" "F.Mask" "F.Paste")
			(net "M_B_CPU1_SA_DQS_DN<9>")
		)
		(pad "201" smd rect
			(at 2.050034 -15.724886 270)
			(size 0.519938 1.4986)
			(layers "F.Cu" "F.Mask" "F.Paste")
			(net "M_B_CPU1_SA_DQS_DP<9>")
		)
		(pad "202" smd rect
			(at 2.050034 -14.875002 270)
			(size 0.519938 1.4986)
			(layers "F.Cu" "F.Mask" "F.Paste")
			(net "GND")
		)
		(pad "203" smd rect
			(at 2.050034 -14.025118 270)
			(size 0.519938 1.4986)
			(layers "F.Cu" "F.Mask" "F.Paste")
			(net "M_B_CPU1_SA_CB<6>")
		)
		(pad "204" smd rect
			(at 2.050034 -13.17498 270)
			(size 0.519938 1.4986)
			(layers "F.Cu" "F.Mask" "F.Paste")
			(net "GND")
		)
		(pad "205" smd rect
			(at 2.050034 -12.325096 270)
			(size 0.519938 1.4986)
			(layers "F.Cu" "F.Mask" "F.Paste")
			(net "M_B_CPU1_SA_CB<7>")
		)
		(pad "206" smd rect
			(at 2.050034 -11.474958 270)
			(size 0.519938 1.4986)
			(layers "F.Cu" "F.Mask" "F.Paste")
			(net "GND")
		)
		(pad "207" smd rect
			(at 2.050034 -10.625074 270)
			(size 0.519938 1.4986)
			(layers "F.Cu" "F.Mask" "F.Paste")
			(net "RST_M_AB_CPU1_FPGA_N")
		)
		(pad "208" smd rect
			(at 2.050034 -9.774936 270)
			(size 0.519938 1.4986)
			(layers "F.Cu" "F.Mask" "F.Paste")
			(net "GND")
		)
		(pad "209" smd rect
			(at 2.050034 -8.925052 270)
			(size 0.519938 1.4986)
			(layers "F.Cu" "F.Mask" "F.Paste")
			(net "M_B_CPU1_SA_CS_N<1>")
		)
		(pad "210" smd rect
			(at 2.050034 -8.074914 270)
			(size 0.519938 1.4986)
			(layers "F.Cu" "F.Mask" "F.Paste")
			(net "GND")
		)
		(pad "211" smd rect
			(at 2.050034 -7.22503 270)
			(size 0.519938 1.4986)
			(layers "F.Cu" "F.Mask" "F.Paste")
			(net "M_B_CPU1_SA_CA<1>")
		)
		(pad "212" smd rect
			(at 2.050034 -6.374892 270)
			(size 0.519938 1.4986)
			(layers "F.Cu" "F.Mask" "F.Paste")
			(net "GND")
		)
		(pad "213" smd rect
			(at 2.050034 -5.525008 270)
			(size 0.519938 1.4986)
			(layers "F.Cu" "F.Mask" "F.Paste")
			(net "M_B_CPU1_SA_CA<3>")
		)
		(pad "214" smd rect
			(at 2.050034 -4.675124 270)
			(size 0.519938 1.4986)
			(layers "F.Cu" "F.Mask" "F.Paste")
			(net "GND")
		)
		(pad "215" smd rect
			(at 2.050034 -3.824986 270)
			(size 0.519938 1.4986)
			(layers "F.Cu" "F.Mask" "F.Paste")
			(net "M_B_CPU1_SA_CA<5>")
		)
		(pad "216" smd rect
			(at 2.050034 -2.975102 270)
			(size 0.519938 1.4986)
			(layers "F.Cu" "F.Mask" "F.Paste")
			(net "GND")
		)
		(pad "217" smd rect
			(at 2.050034 -2.124964 270)
			(size 0.519938 1.4986)
			(layers "F.Cu" "F.Mask" "F.Paste")
			(net "M_B_CPU1_CLK_DP<0>")
		)
		(pad "218" smd rect
			(at 2.050034 -1.27508 270)
			(size 0.519938 1.4986)
			(layers "F.Cu" "F.Mask" "F.Paste")
			(net "M_B_CPU1_CLK_DN<0>")
		)
		(pad "219" smd rect
			(at 2.050034 -0.424942 270)
			(size 0.519938 1.4986)
			(layers "F.Cu" "F.Mask" "F.Paste")
			(net "GND")
		)
		(pad "220" smd rect
			(at 2.050034 5.525008 270)
			(size 0.519938 1.4986)
			(layers "F.Cu" "F.Mask" "F.Paste")
			(net "TP_CHB_CPU1_DIMM1_FRU_4")
		)
		(pad "221" smd rect
			(at 2.050034 6.374892 270)
			(size 0.519938 1.4986)
			(layers "F.Cu" "F.Mask" "F.Paste")
			(net "M_B_CPU1_SB_CA<1>")
		)
		(pad "222" smd rect
			(at 2.050034 7.22503 270)
			(size 0.519938 1.4986)
			(layers "F.Cu" "F.Mask" "F.Paste")
			(net "GND")
		)
		(pad "223" smd rect
			(at 2.050034 8.074914 270)
			(size 0.519938 1.4986)
			(layers "F.Cu" "F.Mask" "F.Paste")
			(net "M_B_CPU1_SB_CA<3>")
		)
		(pad "224" smd rect
			(at 2.050034 8.925052 270)
			(size 0.519938 1.4986)
			(layers "F.Cu" "F.Mask" "F.Paste")
			(net "GND")
		)
	)
)
